(kicad_pcb
	(version 20260206)
	(generator "pcbnew")
	(generator_version "10.0")
	(general
		(thickness 1.6)
		(legacy_teardrops no)
	)
	(paper "A4")
	(title_block
		(title "panther-plus-userver — 13130-1b_20150205.brd")
		(comment 1 "Honey Badger (Wiwynn) / footprint 406 of 1509 (DIMM2), pads 93-99 of 210")
	)
	(layers
		(0 "F.Cu" signal "TOP")
		(4 "In1.Cu" signal "L2")
		(6 "In2.Cu" signal "L3")
		(8 "In3.Cu" signal "L4")
		(10 "In4.Cu" signal "L5")
		(12 "In5.Cu" signal "L6")
		(14 "In6.Cu" signal "L7")
		(16 "In7.Cu" signal "L8")
		(18 "In8.Cu" signal "L9")
		(20 "In9.Cu" signal "L10")
		(22 "In10.Cu" signal "L11")
		(2 "B.Cu" signal "BOTTOM")
		(9 "F.Adhes" user "F.Adhesive")
		(11 "B.Adhes" user "B.Adhesive")
		(13 "F.Paste" user "Package Geometry/Pastemask Top")
		(15 "B.Paste" user "Package Geometry/Pastemask Bottom")
		(5 "F.SilkS" user "Ref Des/Silkscreen Top")
		(7 "B.SilkS" user "Ref Des/Silkscreen Bottom")
		(1 "F.Mask" user "Board Geometry/Soldermask Top")
		(3 "B.Mask" user "Board Geometry/Soldermask Bottom")
		(17 "Dwgs.User" user "User.Drawings")
		(19 "Cmts.User" user "User.Comments")
		(21 "Eco1.User" user "User.Eco1")
		(23 "Eco2.User" user "User.Eco2")
		(25 "Edge.Cuts" user "Board Geometry/Outline")
		(27 "Margin" user)
		(31 "F.CrtYd" user "Package Geometry/Place Bound Top")
		(29 "B.CrtYd" user "Package Geometry/Place Bound Bottom")
		(35 "F.Fab" user "Ref Des/Assembly Top")
		(33 "B.Fab" user "Ref Des/Assembly Bottom")
	)
	(footprint ""
		(layer "F.Cu")
		(at 158.500064 -66.699892 180)
		(property "Reference" "DIMM2"
			(at 0 0 180)
			(layer "F.SilkS")
			(hide yes)
			(effects
				(font
					(size 1.27 1.27)
				)
			)
		)
		(property "Value" "DDR3-204P-174-COLAY-1-GP"
			(at -40.682164 -17.468088 180)
			(unlocked yes)
			(layer "F.Fab")
			(hide yes)
			(effects
				(font
					(size 1.016 1.016)
					(thickness 0.1524)
				)
			)
		)
		(property "Device Type" "AS0A626-H8SN-7H-COLAY-1"
			(at -40.682164 -18.992088 180)
			(unlocked yes)
			(layer "F.Fab")
			(hide yes)
			(effects
				(font
					(size 1.016 1.016)
					(thickness 0.1524)
				)
			)
		)
		(duplicate_pad_numbers_are_jumpers no)
		(pad "91" smd custom
			(at -2.249932 4.106672 180)
			(size 0.1143 0.1143)
			(layers "F.Cu" "F.Mask" "F.Paste")
			(net "M_A_BS2")
			(options
				(clearance outline)
				(anchor circle)
			)
			(primitives
				(gr_poly
					(pts
						(xy 0 0.9017) (xy -0.03175 0.89916) (xy -0.0635 0.889) (xy -0.09144 0.87376) (xy -0.11684 0.85344)
						(xy -0.13716 0.82804) (xy -0.1524 0.8001) (xy -0.16256 0.76835) (xy -0.1651 0.7366) (xy -0.1651 0.11938)
						(xy -0.17272 0.11176) (xy -0.19812 0.0762) (xy -0.2032 0.06604) (xy -0.20701 0.05715) (xy -0.21209 0.04699)
						(xy -0.2159 0.03683) (xy -0.21844 0.02667) (xy -0.22225 0.01524) (xy -0.22352 0.00508) (xy -0.22606 -0.00508)
						(xy -0.22733 -0.01651) (xy -0.22733 -0.02667) (xy -0.2286 -0.0381) (xy -0.22733 -0.04953) (xy -0.22733 -0.05969)
						(xy -0.22606 -0.07112) (xy -0.22352 -0.08128) (xy -0.22225 -0.09144) (xy -0.21844 -0.10287) (xy -0.2159 -0.11303)
						(xy -0.21209 -0.12319) (xy -0.20701 -0.13335) (xy -0.2032 -0.14224) (xy -0.19812 -0.1524) (xy -0.17272 -0.18796)
						(xy -0.1651 -0.19558) (xy -0.1651 -0.7366) (xy -0.16256 -0.76835) (xy -0.1524 -0.8001) (xy -0.13716 -0.82804)
						(xy -0.11684 -0.85344) (xy -0.09144 -0.87376) (xy -0.0635 -0.889) (xy -0.03175 -0.89916) (xy 0 -0.9017)
						(xy 0.03175 -0.89916) (xy 0.0635 -0.889) (xy 0.09144 -0.87376) (xy 0.11684 -0.85344) (xy 0.13716 -0.82804)
						(xy 0.1524 -0.8001) (xy 0.16256 -0.76835) (xy 0.1651 -0.7366) (xy 0.1651 -0.19685) (xy 0.17272 -0.18923)
						(xy 0.17907 -0.18034) (xy 0.18669 -0.17145) (xy 0.19177 -0.16256) (xy 0.19812 -0.15367) (xy 0.20828 -0.13335)
						(xy 0.21971 -0.10287) (xy 0.22225 -0.09271) (xy 0.22479 -0.08128) (xy 0.22606 -0.07112) (xy 0.2286 -0.05969)
						(xy 0.2286 -0.01651) (xy 0.22606 -0.00508) (xy 0.22479 0.00508) (xy 0.22225 0.01651) (xy 0.21971 0.02667)
						(xy 0.20828 0.05715) (xy 0.19812 0.07747) (xy 0.19177 0.08636) (xy 0.18669 0.09525) (xy 0.17907 0.10414)
						(xy 0.17272 0.11303) (xy 0.1651 0.12065) (xy 0.1651 0.7366) (xy 0.16256 0.76835) (xy 0.1524 0.8001)
						(xy 0.13716 0.82804) (xy 0.11684 0.85344) (xy 0.09144 0.87376) (xy 0.0635 0.889) (xy 0.03175 0.89916)
					)
					(width 0)
					(fill yes)
				)
			)
		)
		(pad "92" smd custom
			(at -1.949958 -4.106672 180)
			(size 0.1143 0.1143)
			(layers "F.Cu" "F.Mask" "F.Paste")
			(net "M_A_MA9")
			(options
				(clearance outline)
				(anchor circle)
			)
			(primitives
				(gr_poly
					(pts
						(xy 0 0.9017) (xy -0.03175 0.89916) (xy -0.0635 0.889) (xy -0.09144 0.87376) (xy -0.11684 0.85344)
						(xy -0.13716 0.82804) (xy -0.1524 0.8001) (xy -0.16256 0.76835) (xy -0.1651 0.7366) (xy -0.1651 0.19685)
						(xy -0.17272 0.18923) (xy -0.17907 0.18034) (xy -0.18669 0.17145) (xy -0.19177 0.16256) (xy -0.19812 0.15367)
						(xy -0.20828 0.13335) (xy -0.21971 0.10287) (xy -0.22225 0.09271) (xy -0.22479 0.08128) (xy -0.22606 0.07112)
						(xy -0.2286 0.05969) (xy -0.2286 0.01651) (xy -0.22606 0.00508) (xy -0.22479 -0.00508) (xy -0.22225 -0.01651)
						(xy -0.21971 -0.02667) (xy -0.20828 -0.05715) (xy -0.19812 -0.07747) (xy -0.19177 -0.08636) (xy -0.18669 -0.09525)
						(xy -0.17907 -0.10414) (xy -0.17272 -0.11303) (xy -0.1651 -0.12065) (xy -0.1651 -0.7366) (xy -0.16256 -0.76835)
						(xy -0.1524 -0.8001) (xy -0.13716 -0.82804) (xy -0.11684 -0.85344) (xy -0.09144 -0.87376) (xy -0.0635 -0.889)
						(xy -0.03175 -0.89916) (xy 0 -0.9017) (xy 0.03175 -0.89916) (xy 0.0635 -0.889) (xy 0.09144 -0.87376)
						(xy 0.11684 -0.85344) (xy 0.13716 -0.82804) (xy 0.1524 -0.8001) (xy 0.16256 -0.76835) (xy 0.1651 -0.7366)
						(xy 0.1651 -0.11938) (xy 0.17272 -0.11176) (xy 0.19812 -0.0762) (xy 0.2032 -0.06604) (xy 0.20701 -0.05715)
						(xy 0.21209 -0.04699) (xy 0.2159 -0.03683) (xy 0.21844 -0.02667) (xy 0.22225 -0.01524) (xy 0.22352 -0.00508)
						(xy 0.22606 0.00508) (xy 0.22733 0.01651) (xy 0.22733 0.02667) (xy 0.2286 0.0381) (xy 0.22733 0.04953)
						(xy 0.22733 0.05969) (xy 0.22606 0.07112) (xy 0.22352 0.08128) (xy 0.22225 0.09144) (xy 0.21844 0.10287)
						(xy 0.2159 0.11303) (xy 0.21209 0.12319) (xy 0.20701 0.13335) (xy 0.2032 0.14224) (xy 0.19812 0.1524)
						(xy 0.17272 0.18796) (xy 0.1651 0.19558) (xy 0.1651 0.7366) (xy 0.16256 0.76835) (xy 0.1524 0.8001)
						(xy 0.13716 0.82804) (xy 0.11684 0.85344) (xy 0.09144 0.87376) (xy 0.0635 0.889) (xy 0.03175 0.89916)
					)
					(width 0)
					(fill yes)
				)
			)
		)
		(pad "93" smd custom
			(at -1.649984 4.106672 180)
			(size 0.1143 0.1143)
			(layers "F.Cu" "F.Mask" "F.Paste")
			(net "PV_VDDR")
			(options
				(clearance outline)
				(anchor circle)
			)
			(primitives
				(gr_poly
					(pts
						(xy 0 0.9017) (xy -0.03175 0.89916) (xy -0.0635 0.889) (xy -0.09144 0.87376) (xy -0.11684 0.85344)
						(xy -0.13716 0.82804) (xy -0.1524 0.8001) (xy -0.16256 0.76835) (xy -0.1651 0.7366) (xy -0.1651 -0.13462)
						(xy -0.17272 -0.14224) (xy -0.19812 -0.1778) (xy -0.2032 -0.18796) (xy -0.20701 -0.19685) (xy -0.21209 -0.20701)
						(xy -0.2159 -0.21717) (xy -0.21844 -0.22733) (xy -0.22225 -0.23876) (xy -0.22352 -0.24892) (xy -0.22606 -0.25908)
						(xy -0.22733 -0.27051) (xy -0.22733 -0.28067) (xy -0.2286 -0.2921) (xy -0.22733 -0.30353) (xy -0.22733 -0.31369)
						(xy -0.22606 -0.32512) (xy -0.22352 -0.33528) (xy -0.22225 -0.34544) (xy -0.21844 -0.35687) (xy -0.2159 -0.36703)
						(xy -0.21209 -0.37719) (xy -0.20701 -0.38735) (xy -0.2032 -0.39624) (xy -0.19812 -0.4064) (xy -0.17272 -0.44196)
						(xy -0.1651 -0.44958) (xy -0.1651 -0.7366) (xy -0.16256 -0.76835) (xy -0.1524 -0.8001) (xy -0.13716 -0.82804)
						(xy -0.11684 -0.85344) (xy -0.09144 -0.87376) (xy -0.0635 -0.889) (xy -0.03175 -0.89916) (xy 0 -0.9017)
						(xy 0.03175 -0.89916) (xy 0.0635 -0.889) (xy 0.09144 -0.87376) (xy 0.11684 -0.85344) (xy 0.13716 -0.82804)
						(xy 0.1524 -0.8001) (xy 0.16256 -0.76835) (xy 0.1651 -0.7366) (xy 0.1651 -0.44958) (xy 0.17272 -0.44196)
						(xy 0.19812 -0.4064) (xy 0.2032 -0.39624) (xy 0.20701 -0.38735) (xy 0.21209 -0.37719) (xy 0.2159 -0.36703)
						(xy 0.21844 -0.35687) (xy 0.22225 -0.34544) (xy 0.22352 -0.33528) (xy 0.22606 -0.32512) (xy 0.22733 -0.31369)
						(xy 0.22733 -0.30353) (xy 0.2286 -0.2921) (xy 0.22733 -0.28067) (xy 0.22733 -0.27051) (xy 0.22606 -0.25908)
						(xy 0.22352 -0.24892) (xy 0.22225 -0.23876) (xy 0.21844 -0.22733) (xy 0.2159 -0.21717) (xy 0.21209 -0.20701)
						(xy 0.20701 -0.19685) (xy 0.2032 -0.18796) (xy 0.19812 -0.1778) (xy 0.17272 -0.14224) (xy 0.1651 -0.13462)
						(xy 0.1651 0.7366) (xy 0.16256 0.76835) (xy 0.1524 0.8001) (xy 0.13716 0.82804) (xy 0.11684 0.85344)
						(xy 0.09144 0.87376) (xy 0.0635 0.889) (xy 0.03175 0.89916)
					)
					(width 0)
					(fill yes)
				)
			)
		)
		(pad "94" smd custom
			(at -1.35001 -4.106672 180)
			(size 0.1143 0.1143)
			(layers "F.Cu" "F.Mask" "F.Paste")
			(net "PV_VDDR")
			(options
				(clearance outline)
				(anchor circle)
			)
			(primitives
				(gr_poly
					(pts
						(xy 0 0.9017) (xy -0.03175 0.89916) (xy -0.0635 0.889) (xy -0.09144 0.87376) (xy -0.11684 0.85344)
						(xy -0.13716 0.82804) (xy -0.1524 0.8001) (xy -0.16256 0.76835) (xy -0.1651 0.7366) (xy -0.1651 0.44958)
						(xy -0.17272 0.44196) (xy -0.19812 0.4064) (xy -0.2032 0.39624) (xy -0.20701 0.38735) (xy -0.21209 0.37719)
						(xy -0.2159 0.36703) (xy -0.21844 0.35687) (xy -0.22225 0.34544) (xy -0.22352 0.33528) (xy -0.22606 0.32512)
						(xy -0.22733 0.31369) (xy -0.22733 0.30353) (xy -0.2286 0.2921) (xy -0.22733 0.28067) (xy -0.22733 0.27051)
						(xy -0.22606 0.25908) (xy -0.22352 0.24892) (xy -0.22225 0.23876) (xy -0.21844 0.22733) (xy -0.2159 0.21717)
						(xy -0.21209 0.20701) (xy -0.20701 0.19685) (xy -0.2032 0.18796) (xy -0.19812 0.1778) (xy -0.17272 0.14224)
						(xy -0.1651 0.13462) (xy -0.1651 -0.7366) (xy -0.16256 -0.76835) (xy -0.1524 -0.8001) (xy -0.13716 -0.82804)
						(xy -0.11684 -0.85344) (xy -0.09144 -0.87376) (xy -0.0635 -0.889) (xy -0.03175 -0.89916) (xy 0 -0.9017)
						(xy 0.03175 -0.89916) (xy 0.0635 -0.889) (xy 0.09144 -0.87376) (xy 0.11684 -0.85344) (xy 0.13716 -0.82804)
						(xy 0.1524 -0.8001) (xy 0.16256 -0.76835) (xy 0.1651 -0.7366) (xy 0.1651 0.13462) (xy 0.17272 0.14224)
						(xy 0.19812 0.1778) (xy 0.2032 0.18796) (xy 0.20701 0.19685) (xy 0.21209 0.20701) (xy 0.2159 0.21717)
						(xy 0.21844 0.22733) (xy 0.22225 0.23876) (xy 0.22352 0.24892) (xy 0.22606 0.25908) (xy 0.22733 0.27051)
						(xy 0.22733 0.28067) (xy 0.2286 0.2921) (xy 0.22733 0.30353) (xy 0.22733 0.31369) (xy 0.22606 0.32512)
						(xy 0.22352 0.33528) (xy 0.22225 0.34544) (xy 0.21844 0.35687) (xy 0.2159 0.36703) (xy 0.21209 0.37719)
						(xy 0.20701 0.38735) (xy 0.2032 0.39624) (xy 0.19812 0.4064) (xy 0.17272 0.44196) (xy 0.1651 0.44958)
						(xy 0.1651 0.7366) (xy 0.16256 0.76835) (xy 0.1524 0.8001) (xy 0.13716 0.82804) (xy 0.11684 0.85344)
						(xy 0.09144 0.87376) (xy 0.0635 0.889) (xy 0.03175 0.89916)
					)
					(width 0)
					(fill yes)
				)
			)
		)
		(pad "95" smd custom
			(at -1.050036 4.106672 180)
			(size 0.1143 0.1143)
			(layers "F.Cu" "F.Mask" "F.Paste")
			(net "M_A_MA12")
			(options
				(clearance outline)
				(anchor circle)
			)
			(primitives
				(gr_poly
					(pts
						(xy 0 0.9017) (xy -0.03175 0.89916) (xy -0.0635 0.889) (xy -0.09144 0.87376) (xy -0.11684 0.85344)
						(xy -0.13716 0.82804) (xy -0.1524 0.8001) (xy -0.16256 0.76835) (xy -0.1651 0.7366) (xy -0.1651 0.11938)
						(xy -0.17272 0.11176) (xy -0.19812 0.0762) (xy -0.2032 0.06604) (xy -0.20701 0.05715) (xy -0.21209 0.04699)
						(xy -0.2159 0.03683) (xy -0.21844 0.02667) (xy -0.22225 0.01524) (xy -0.22352 0.00508) (xy -0.22606 -0.00508)
						(xy -0.22733 -0.01651) (xy -0.22733 -0.02667) (xy -0.2286 -0.0381) (xy -0.22733 -0.04953) (xy -0.22733 -0.05969)
						(xy -0.22606 -0.07112) (xy -0.22352 -0.08128) (xy -0.22225 -0.09144) (xy -0.21844 -0.10287) (xy -0.2159 -0.11303)
						(xy -0.21209 -0.12319) (xy -0.20701 -0.13335) (xy -0.2032 -0.14224) (xy -0.19812 -0.1524) (xy -0.17272 -0.18796)
						(xy -0.1651 -0.19558) (xy -0.1651 -0.7366) (xy -0.16256 -0.76835) (xy -0.1524 -0.8001) (xy -0.13716 -0.82804)
						(xy -0.11684 -0.85344) (xy -0.09144 -0.87376) (xy -0.0635 -0.889) (xy -0.03175 -0.89916) (xy 0 -0.9017)
						(xy 0.03175 -0.89916) (xy 0.0635 -0.889) (xy 0.09144 -0.87376) (xy 0.11684 -0.85344) (xy 0.13716 -0.82804)
						(xy 0.1524 -0.8001) (xy 0.16256 -0.76835) (xy 0.1651 -0.7366) (xy 0.1651 -0.19685) (xy 0.17272 -0.18923)
						(xy 0.17907 -0.18034) (xy 0.18669 -0.17145) (xy 0.19177 -0.16256) (xy 0.19812 -0.15367) (xy 0.20828 -0.13335)
						(xy 0.21971 -0.10287) (xy 0.22225 -0.09271) (xy 0.22479 -0.08128) (xy 0.22606 -0.07112) (xy 0.2286 -0.05969)
						(xy 0.2286 -0.01651) (xy 0.22606 -0.00508) (xy 0.22479 0.00508) (xy 0.22225 0.01651) (xy 0.21971 0.02667)
						(xy 0.20828 0.05715) (xy 0.19812 0.07747) (xy 0.19177 0.08636) (xy 0.18669 0.09525) (xy 0.17907 0.10414)
						(xy 0.17272 0.11303) (xy 0.1651 0.12065) (xy 0.1651 0.7366) (xy 0.16256 0.76835) (xy 0.1524 0.8001)
						(xy 0.13716 0.82804) (xy 0.11684 0.85344) (xy 0.09144 0.87376) (xy 0.0635 0.889) (xy 0.03175 0.89916)
					)
					(width 0)
					(fill yes)
				)
			)
		)
		(pad "96" smd custom
			(at -0.750062 -4.106672 180)
			(size 0.1143 0.1143)
			(layers "F.Cu" "F.Mask" "F.Paste")
			(net "M_A_MA11")
			(options
				(clearance outline)
				(anchor circle)
			)
			(primitives
				(gr_poly
					(pts
						(xy 0 0.9017) (xy -0.03175 0.89916) (xy -0.0635 0.889) (xy -0.09144 0.87376) (xy -0.11684 0.85344)
						(xy -0.13716 0.82804) (xy -0.1524 0.8001) (xy -0.16256 0.76835) (xy -0.1651 0.7366) (xy -0.1651 0.19685)
						(xy -0.17272 0.18923) (xy -0.17907 0.18034) (xy -0.18669 0.17145) (xy -0.19177 0.16256) (xy -0.19812 0.15367)
						(xy -0.20828 0.13335) (xy -0.21971 0.10287) (xy -0.22225 0.09271) (xy -0.22479 0.08128) (xy -0.22606 0.07112)
						(xy -0.2286 0.05969) (xy -0.2286 0.01651) (xy -0.22606 0.00508) (xy -0.22479 -0.00508) (xy -0.22225 -0.01651)
						(xy -0.21971 -0.02667) (xy -0.20828 -0.05715) (xy -0.19812 -0.07747) (xy -0.19177 -0.08636) (xy -0.18669 -0.09525)
						(xy -0.17907 -0.10414) (xy -0.17272 -0.11303) (xy -0.1651 -0.12065) (xy -0.1651 -0.7366) (xy -0.16256 -0.76835)
						(xy -0.1524 -0.8001) (xy -0.13716 -0.82804) (xy -0.11684 -0.85344) (xy -0.09144 -0.87376) (xy -0.0635 -0.889)
						(xy -0.03175 -0.89916) (xy 0 -0.9017) (xy 0.03175 -0.89916) (xy 0.0635 -0.889) (xy 0.09144 -0.87376)
						(xy 0.11684 -0.85344) (xy 0.13716 -0.82804) (xy 0.1524 -0.8001) (xy 0.16256 -0.76835) (xy 0.1651 -0.7366)
						(xy 0.1651 -0.11938) (xy 0.17272 -0.11176) (xy 0.19812 -0.0762) (xy 0.2032 -0.06604) (xy 0.20701 -0.05715)
						(xy 0.21209 -0.04699) (xy 0.2159 -0.03683) (xy 0.21844 -0.02667) (xy 0.22225 -0.01524) (xy 0.22352 -0.00508)
						(xy 0.22606 0.00508) (xy 0.22733 0.01651) (xy 0.22733 0.02667) (xy 0.2286 0.0381) (xy 0.22733 0.04953)
						(xy 0.22733 0.05969) (xy 0.22606 0.07112) (xy 0.22352 0.08128) (xy 0.22225 0.09144) (xy 0.21844 0.10287)
						(xy 0.2159 0.11303) (xy 0.21209 0.12319) (xy 0.20701 0.13335) (xy 0.2032 0.14224) (xy 0.19812 0.1524)
						(xy 0.17272 0.18796) (xy 0.1651 0.19558) (xy 0.1651 0.7366) (xy 0.16256 0.76835) (xy 0.1524 0.8001)
						(xy 0.13716 0.82804) (xy 0.11684 0.85344) (xy 0.09144 0.87376) (xy 0.0635 0.889) (xy 0.03175 0.89916)
					)
					(width 0)
					(fill yes)
				)
			)
		)
		(pad "97" smd custom
			(at -0.450088 4.106672 180)
			(size 0.1143 0.1143)
			(layers "F.Cu" "F.Mask" "F.Paste")
			(net "M_A_MA8")
			(options
				(clearance outline)
				(anchor circle)
			)
			(primitives
				(gr_poly
					(pts
						(xy 0 0.9017) (xy -0.03175 0.89916) (xy -0.0635 0.889) (xy -0.09144 0.87376) (xy -0.11684 0.85344)
						(xy -0.13716 0.82804) (xy -0.1524 0.8001) (xy -0.16256 0.76835) (xy -0.1651 0.7366) (xy -0.1651 -0.13462)
						(xy -0.17272 -0.14224) (xy -0.19812 -0.1778) (xy -0.2032 -0.18796) (xy -0.20701 -0.19685) (xy -0.21209 -0.20701)
						(xy -0.2159 -0.21717) (xy -0.21844 -0.22733) (xy -0.22225 -0.23876) (xy -0.22352 -0.24892) (xy -0.22606 -0.25908)
						(xy -0.22733 -0.27051) (xy -0.22733 -0.28067) (xy -0.2286 -0.2921) (xy -0.22733 -0.30353) (xy -0.22733 -0.31369)
						(xy -0.22606 -0.32512) (xy -0.22352 -0.33528) (xy -0.22225 -0.34544) (xy -0.21844 -0.35687) (xy -0.2159 -0.36703)
						(xy -0.21209 -0.37719) (xy -0.20701 -0.38735) (xy -0.2032 -0.39624) (xy -0.19812 -0.4064) (xy -0.17272 -0.44196)
						(xy -0.1651 -0.44958) (xy -0.1651 -0.7366) (xy -0.16256 -0.76835) (xy -0.1524 -0.8001) (xy -0.13716 -0.82804)
						(xy -0.11684 -0.85344) (xy -0.09144 -0.87376) (xy -0.0635 -0.889) (xy -0.03175 -0.89916) (xy 0 -0.9017)
						(xy 0.03175 -0.89916) (xy 0.0635 -0.889) (xy 0.09144 -0.87376) (xy 0.11684 -0.85344) (xy 0.13716 -0.82804)
						(xy 0.1524 -0.8001) (xy 0.16256 -0.76835) (xy 0.1651 -0.7366) (xy 0.1651 -0.44958) (xy 0.17272 -0.44196)
						(xy 0.19812 -0.4064) (xy 0.2032 -0.39624) (xy 0.20701 -0.38735) (xy 0.21209 -0.37719) (xy 0.2159 -0.36703)
						(xy 0.21844 -0.35687) (xy 0.22225 -0.34544) (xy 0.22352 -0.33528) (xy 0.22606 -0.32512) (xy 0.22733 -0.31369)
						(xy 0.22733 -0.30353) (xy 0.2286 -0.2921) (xy 0.22733 -0.28067) (xy 0.22733 -0.27051) (xy 0.22606 -0.25908)
						(xy 0.22352 -0.24892) (xy 0.22225 -0.23876) (xy 0.21844 -0.22733) (xy 0.2159 -0.21717) (xy 0.21209 -0.20701)
						(xy 0.20701 -0.19685) (xy 0.2032 -0.18796) (xy 0.19812 -0.1778) (xy 0.17272 -0.14224) (xy 0.1651 -0.13462)
						(xy 0.1651 0.7366) (xy 0.16256 0.76835) (xy 0.1524 0.8001) (xy 0.13716 0.82804) (xy 0.11684 0.85344)
						(xy 0.09144 0.87376) (xy 0.0635 0.889) (xy 0.03175 0.89916)
					)
					(width 0)
					(fill yes)
				)
			)
		)
	)
)
